# T6G (Grand Teton) — schematic netlist excerpt (pin names and nets, part order shuffled) for the footprints in the layout excerpt that follows; sources: Cadence DE-HDL packaged netlist, KiCad conversion of 04192023_DAF0TMB3IC0_F0TG_MB_C_brd_V02_OCP.brd

C6546  Q_CAP_DIFFBUS  DIFF BUS_0.22UF 6.3V 20% X6S  pkg C0201  page 286 : \1\ = P5E_CPU0_P1_TX_BUF_C_DN<6> ; \2\ = P5E_CPU0_P1_TX_BUF_DN<6>
C2105  Q_CAP  22UF 4V 20% X6S  pkg C0402  page 74 : A = PVDDIO_P1 ; B = GND
C511  Q_CAP  4.7UF 6.3V 20% X6S  pkg 0402  page 279 : A = P1V8_CPU0_RT_1D ; B = GND

(kicad_pcb
	(version 20260206)
	(generator "pcbnew")
	(generator_version "10.0")
	(general
		(thickness 1.6)
		(legacy_teardrops no)
	)
	(paper "A4")
	(title_block
		(title "04192023_DAF0TMB3IC0_F0TG_MB_C_brd_V02_OCP.brd")
		(comment 1 "Grand Teton / footprints 5976-5978 of 8354")
	)
	(layers
		(0 "F.Cu" signal "TOP")
		(4 "In1.Cu" signal "GND")
		(6 "In2.Cu" signal "IN1")
		(8 "In3.Cu" signal "GND1")
		(10 "In4.Cu" signal "IN2")
		(12 "In5.Cu" signal "GND2")
		(14 "In6.Cu" signal "IN3")
		(16 "In7.Cu" signal "GND3")
		(18 "In8.Cu" signal "VCC")
		(20 "In9.Cu" signal "VCC1")
		(22 "In10.Cu" signal "GND4")
		(24 "In11.Cu" signal "IN4")
		(26 "In12.Cu" signal "GND5")
		(28 "In13.Cu" signal "IN5")
		(30 "In14.Cu" signal "GND6")
		(32 "In15.Cu" signal "IN6")
		(34 "In16.Cu" signal "GND7")
		(2 "B.Cu" signal "BOTTOM")
		(9 "F.Adhes" user "F.Adhesive")
		(11 "B.Adhes" user "B.Adhesive")
		(13 "F.Paste" user "Package Geometry/Pastemask Top")
		(15 "B.Paste" user "Package Geometry/Pastemask Bottom")
		(5 "F.SilkS" user "Ref Des/Silkscreen Top")
		(7 "B.SilkS" user "Ref Des/Silkscreen Bottom")
		(1 "F.Mask" user "Board Geometry/Soldermask Top")
		(3 "B.Mask" user "Board Geometry/Soldermask Bottom")
		(17 "Dwgs.User" user "User.Drawings")
		(19 "Cmts.User" user "User.Comments")
		(21 "Eco1.User" user "User.Eco1")
		(23 "Eco2.User" user "User.Eco2")
		(25 "Edge.Cuts" user "Board Geometry/Outline")
		(27 "Margin" user)
		(31 "F.CrtYd" user "Package Geometry/Place Bound Top")
		(29 "B.CrtYd" user "Package Geometry/Place Bound Bottom")
		(35 "F.Fab" user "Ref Des/Assembly Top")
		(33 "B.Fab" user "Ref Des/Assembly Bottom")
	)
	(footprint ""
		(layer "B.Cu")
		(at 100.271834 -263.521952)
		(property "Reference" "C2105"
			(at 0 0 0)
			(layer "B.SilkS")
			(hide yes)
			(effects
				(font
					(size 1.27 1.27)
				)
				(justify mirror)
			)
		)
		(property "Value" ""
			(at 0 0 0)
			(layer "B.Fab")
			(effects
				(font
					(size 1.27 1.27)
				)
				(justify mirror)
			)
		)
		(duplicate_pad_numbers_are_jumpers no)
		(fp_line
			(start -0.7874 -0.4064)
			(end -0.7874 0.4064)
			(stroke
				(width 0.1524)
				(type default)
			)
			(layer "B.SilkS")
		)
		(fp_line
			(start -0.7874 0.4064)
			(end 0.7874 0.4064)
			(stroke
				(width 0.1524)
				(type default)
			)
			(layer "B.SilkS")
		)
		(fp_line
			(start 0.7874 -0.4064)
			(end -0.7874 -0.4064)
			(stroke
				(width 0.1524)
				(type default)
			)
			(layer "B.SilkS")
		)
		(fp_line
			(start 0.7874 0.4064)
			(end 0.7874 -0.4064)
			(stroke
				(width 0.1524)
				(type default)
			)
			(layer "B.SilkS")
		)
		(fp_line
			(start -0.67945 -0.3048)
			(end -0.67945 0.3048)
			(stroke
				(width 0.1)
				(type default)
			)
			(layer "B.Fab")
		)
		(fp_line
			(start -0.67945 0.3048)
			(end -0.120396 0.3048)
			(stroke
				(width 0.1)
				(type default)
			)
			(layer "B.Fab")
		)
		(fp_line
			(start -0.12065 -0.3048)
			(end -0.67945 -0.3048)
			(stroke
				(width 0.1)
				(type default)
			)
			(layer "B.Fab")
		)
		(fp_line
			(start -0.12065 -0.2794)
			(end -0.12065 -0.3048)
			(stroke
				(width 0.1)
				(type default)
			)
			(layer "B.Fab")
		)
		(fp_line
			(start -0.120396 0.2794)
			(end 0.12065 0.2794)
			(stroke
				(width 0.1)
				(type default)
			)
			(layer "B.Fab")
		)
		(fp_line
			(start -0.120396 0.3048)
			(end -0.120396 0.2794)
			(stroke
				(width 0.1)
				(type default)
			)
			(layer "B.Fab")
		)
		(fp_line
			(start 0.12065 -0.305054)
			(end 0.12065 -0.2794)
			(stroke
				(width 0.1)
				(type default)
			)
			(layer "B.Fab")
		)
		(fp_line
			(start 0.12065 -0.2794)
			(end -0.12065 -0.2794)
			(stroke
				(width 0.1)
				(type default)
			)
			(layer "B.Fab")
		)
		(fp_line
			(start 0.12065 0.2794)
			(end 0.12065 0.3048)
			(stroke
				(width 0.1)
				(type default)
			)
			(layer "B.Fab")
		)
		(fp_line
			(start 0.12065 0.3048)
			(end 0.67945 0.3048)
			(stroke
				(width 0.1)
				(type default)
			)
			(layer "B.Fab")
		)
		(fp_line
			(start 0.67945 -0.305054)
			(end 0.12065 -0.305054)
			(stroke
				(width 0.1)
				(type default)
			)
			(layer "B.Fab")
		)
		(fp_line
			(start 0.67945 0.3048)
			(end 0.67945 -0.305054)
			(stroke
				(width 0.1)
				(type default)
			)
			(layer "B.Fab")
		)
		(pad "1" smd circle
			(at 0.40005 0 180)
			(size 0 0)
			(layers "B.Cu" "B.Mask" "B.Paste")
			(net "PVDDIO_P1")
		)
		(pad "2" smd circle
			(at -0.40005 0 180)
			(size 0 0)
			(layers "B.Cu" "B.Mask" "B.Paste")
			(net "GND")
		)
	)
	(footprint ""
		(layer "B.Cu")
		(at 328.052176 -395.127988 -90)
		(property "Reference" "C511"
			(at 0 0 90)
			(layer "B.SilkS")
			(hide yes)
			(effects
				(font
					(size 1.27 1.27)
				)
				(justify mirror)
			)
		)
		(property "Value" ""
			(at 0 0 90)
			(layer "B.Fab")
			(effects
				(font
					(size 1.27 1.27)
				)
				(justify mirror)
			)
		)
		(duplicate_pad_numbers_are_jumpers no)
		(fp_line
			(start -0.7874 0.4064)
			(end 0.7874 0.4064)
			(stroke
				(width 0.1524)
				(type default)
			)
			(layer "B.SilkS")
		)
		(fp_line
			(start 0.7874 0.4064)
			(end 0.7874 -0.4064)
			(stroke
				(width 0.1524)
				(type default)
			)
			(layer "B.SilkS")
		)
		(fp_line
			(start -0.7874 -0.4064)
			(end -0.7874 0.4064)
			(stroke
				(width 0.1524)
				(type default)
			)
			(layer "B.SilkS")
		)
		(fp_line
			(start 0.7874 -0.4064)
			(end -0.7874 -0.4064)
			(stroke
				(width 0.1524)
				(type default)
			)
			(layer "B.SilkS")
		)
		(fp_line
			(start -0.67945 0.3048)
			(end -0.120396 0.3048)
			(stroke
				(width 0.1)
				(type default)
			)
			(layer "B.Fab")
		)
		(fp_line
			(start -0.120396 0.3048)
			(end -0.120396 0.2794)
			(stroke
				(width 0.1)
				(type default)
			)
			(layer "B.Fab")
		)
		(fp_line
			(start 0.12065 0.3048)
			(end 0.67945 0.3048)
			(stroke
				(width 0.1)
				(type default)
			)
			(layer "B.Fab")
		)
		(fp_line
			(start 0.67945 0.3048)
			(end 0.67945 -0.305054)
			(stroke
				(width 0.1)
				(type default)
			)
			(layer "B.Fab")
		)
		(fp_line
			(start -0.120396 0.2794)
			(end 0.12065 0.2794)
			(stroke
				(width 0.1)
				(type default)
			)
			(layer "B.Fab")
		)
		(fp_line
			(start 0.12065 0.2794)
			(end 0.12065 0.3048)
			(stroke
				(width 0.1)
				(type default)
			)
			(layer "B.Fab")
		)
		(fp_line
			(start -0.12065 -0.2794)
			(end -0.12065 -0.3048)
			(stroke
				(width 0.1)
				(type default)
			)
			(layer "B.Fab")
		)
		(fp_line
			(start 0.12065 -0.2794)
			(end -0.12065 -0.2794)
			(stroke
				(width 0.1)
				(type default)
			)
			(layer "B.Fab")
		)
		(fp_line
			(start -0.67945 -0.3048)
			(end -0.67945 0.3048)
			(stroke
				(width 0.1)
				(type default)
			)
			(layer "B.Fab")
		)
		(fp_line
			(start -0.12065 -0.3048)
			(end -0.67945 -0.3048)
			(stroke
				(width 0.1)
				(type default)
			)
			(layer "B.Fab")
		)
		(fp_line
			(start 0.12065 -0.305054)
			(end 0.12065 -0.2794)
			(stroke
				(width 0.1)
				(type default)
			)
			(layer "B.Fab")
		)
		(fp_line
			(start 0.67945 -0.305054)
			(end 0.12065 -0.305054)
			(stroke
				(width 0.1)
				(type default)
			)
			(layer "B.Fab")
		)
		(pad "1" smd circle
			(at 0.40005 0 90)
			(size 0 0)
			(layers "B.Cu" "B.Mask" "B.Paste")
			(net "P1V8_CPU0_RT_1D")
		)
		(pad "2" smd circle
			(at -0.40005 0 90)
			(size 0 0)
			(layers "B.Cu" "B.Mask" "B.Paste")
			(net "GND")
		)
	)
	(footprint ""
		(layer "B.Cu")
		(at 323.679566 -416.899344 90)
		(property "Reference" "C6546"
			(at 0 0 90)
			(layer "B.SilkS")
			(hide yes)
			(effects
				(font
					(size 1.27 1.27)
				)
				(justify mirror)
			)
		)
		(property "Value" ""
			(at 0 0 90)
			(layer "B.Fab")
			(effects
				(font
					(size 1.27 1.27)
				)
				(justify mirror)
			)
		)
		(duplicate_pad_numbers_are_jumpers no)
		(fp_line
			(start 0.299974 -0.150114)
			(end -0.299974 -0.150114)
			(stroke
				(width 0.1)
				(type default)
			)
			(layer "B.Fab")
		)
		(fp_line
			(start -0.299974 -0.150114)
			(end -0.299974 0.150114)
			(stroke
				(width 0.1)
				(type default)
			)
			(layer "B.Fab")
		)
		(fp_line
			(start 0.299974 0.150114)
			(end 0.299974 -0.150114)
			(stroke
				(width 0.1)
				(type default)
			)
			(layer "B.Fab")
		)
		(fp_line
			(start -0.299974 0.150114)
			(end 0.299974 0.150114)
			(stroke
				(width 0.1)
				(type default)
			)
			(layer "B.Fab")
		)
		(pad "1" smd rect
			(at 0.2667 0 270)
			(size 0.3048 0.381)
			(layers "B.Cu" "B.Mask" "B.Paste")
			(net "P5E_CPU0_P1_TX_BUF_C_DN<6>")
		)
		(pad "2" smd rect
			(at -0.2667 0 270)
			(size 0.3048 0.381)
			(layers "B.Cu" "B.Mask" "B.Paste")
			(net "P5E_CPU0_P1_TX_BUF_DN<6>")
		)
	)
)
